# S9S_MB_2U (Grand Teton) — schematic netlist excerpt (pin names and nets, part order shuffled) for the footprints in the layout excerpt that follows; sources: Cadence DE-HDL packaged netlist, KiCad conversion of 03242023_DA0F0TMBIJ0_F0T_Motherboard_J_brd_V01_OCP.brd

PR380  Q_RES  2.2 1% CHIP  pkg 0402LF  page 279 : A = PVCCFA_EHV_CPU0_PVCC ; B = PVCCD_HV_CPU0_VDD1
R1525  Q_RES  0 5% CHIP  pkg 0402LF  page 241 : A = SMB_HOST_3V3AUX_SCL_R ; B = SMB_HOST_CLK_3V3AUX_SCL

(kicad_pcb
	(version 20260206)
	(generator "pcbnew")
	(generator_version "10.0")
	(general
		(thickness 1.6)
		(legacy_teardrops no)
	)
	(paper "A4")
	(title_block
		(title "03242023_DA0F0TMBIJ0_F0T_Motherboard_J_brd_V01_OCP.brd")
		(comment 1 "Grand Teton / footprints 5635-5636 of 6105")
	)
	(layers
		(0 "F.Cu" signal "TOP")
		(4 "In1.Cu" signal "GND")
		(6 "In2.Cu" signal "IN1")
		(8 "In3.Cu" signal "GND1")
		(10 "In4.Cu" signal "IN2")
		(12 "In5.Cu" signal "GND2")
		(14 "In6.Cu" signal "IN3")
		(16 "In7.Cu" signal "GND3")
		(18 "In8.Cu" signal "VCC")
		(20 "In9.Cu" signal "VCC1")
		(22 "In10.Cu" signal "GND4")
		(24 "In11.Cu" signal "IN4")
		(26 "In12.Cu" signal "GND5")
		(28 "In13.Cu" signal "IN5")
		(30 "In14.Cu" signal "GND6")
		(32 "In15.Cu" signal "IN6")
		(34 "In16.Cu" signal "GND7")
		(2 "B.Cu" signal "BOTTOM")
		(9 "F.Adhes" user "F.Adhesive")
		(11 "B.Adhes" user "B.Adhesive")
		(13 "F.Paste" user "Package Geometry/Pastemask Top")
		(15 "B.Paste" user "Package Geometry/Pastemask Bottom")
		(5 "F.SilkS" user "Ref Des/Silkscreen Top")
		(7 "B.SilkS" user "Ref Des/Silkscreen Bottom")
		(1 "F.Mask" user "Board Geometry/Soldermask Top")
		(3 "B.Mask" user "Board Geometry/Soldermask Bottom")
		(17 "Dwgs.User" user "User.Drawings")
		(19 "Cmts.User" user "User.Comments")
		(21 "Eco1.User" user "User.Eco1")
		(23 "Eco2.User" user "User.Eco2")
		(25 "Edge.Cuts" user "Board Geometry/Outline")
		(27 "Margin" user)
		(31 "F.CrtYd" user "Package Geometry/Place Bound Top")
		(29 "B.CrtYd" user "Package Geometry/Place Bound Bottom")
		(35 "F.Fab" user "Ref Des/Assembly Top")
		(33 "B.Fab" user "Ref Des/Assembly Bottom")
	)
	(footprint ""
		(layer "B.Cu")
		(at 243.001038 -101.447854 180)
		(property "Reference" "R1525"
			(at 0 0 0)
			(layer "B.SilkS")
			(hide yes)
			(effects
				(font
					(size 1.27 1.27)
				)
				(justify mirror)
			)
		)
		(property "Value" ""
			(at 0 0 0)
			(layer "B.Fab")
			(effects
				(font
					(size 1.27 1.27)
				)
				(justify mirror)
			)
		)
		(duplicate_pad_numbers_are_jumpers no)
		(fp_line
			(start 0.7874 0.4064)
			(end 0.7874 -0.4064)
			(stroke
				(width 0.1524)
				(type default)
			)
			(layer "B.SilkS")
		)
		(fp_line
			(start 0.7874 -0.4064)
			(end -0.7874 -0.4064)
			(stroke
				(width 0.1524)
				(type default)
			)
			(layer "B.SilkS")
		)
		(fp_line
			(start -0.7874 0.4064)
			(end 0.7874 0.4064)
			(stroke
				(width 0.1524)
				(type default)
			)
			(layer "B.SilkS")
		)
		(fp_line
			(start -0.7874 -0.4064)
			(end -0.7874 0.4064)
			(stroke
				(width 0.1524)
				(type default)
			)
			(layer "B.SilkS")
		)
		(fp_line
			(start 0.67945 0.3048)
			(end 0.67945 -0.305054)
			(stroke
				(width 0.1)
				(type default)
			)
			(layer "B.Fab")
		)
		(fp_line
			(start 0.67945 -0.305054)
			(end 0.12065 -0.305054)
			(stroke
				(width 0.1)
				(type default)
			)
			(layer "B.Fab")
		)
		(fp_line
			(start 0.12065 0.3048)
			(end 0.67945 0.3048)
			(stroke
				(width 0.1)
				(type default)
			)
			(layer "B.Fab")
		)
		(fp_line
			(start 0.12065 0.2794)
			(end 0.12065 0.3048)
			(stroke
				(width 0.1)
				(type default)
			)
			(layer "B.Fab")
		)
		(fp_line
			(start 0.12065 -0.2794)
			(end -0.12065 -0.2794)
			(stroke
				(width 0.1)
				(type default)
			)
			(layer "B.Fab")
		)
		(fp_line
			(start 0.12065 -0.305054)
			(end 0.12065 -0.2794)
			(stroke
				(width 0.1)
				(type default)
			)
			(layer "B.Fab")
		)
		(fp_line
			(start -0.120396 0.3048)
			(end -0.120396 0.2794)
			(stroke
				(width 0.1)
				(type default)
			)
			(layer "B.Fab")
		)
		(fp_line
			(start -0.120396 0.2794)
			(end 0.12065 0.2794)
			(stroke
				(width 0.1)
				(type default)
			)
			(layer "B.Fab")
		)
		(fp_line
			(start -0.12065 -0.2794)
			(end -0.12065 -0.3048)
			(stroke
				(width 0.1)
				(type default)
			)
			(layer "B.Fab")
		)
		(fp_line
			(start -0.12065 -0.3048)
			(end -0.67945 -0.3048)
			(stroke
				(width 0.1)
				(type default)
			)
			(layer "B.Fab")
		)
		(fp_line
			(start -0.67945 0.3048)
			(end -0.120396 0.3048)
			(stroke
				(width 0.1)
				(type default)
			)
			(layer "B.Fab")
		)
		(fp_line
			(start -0.67945 -0.3048)
			(end -0.67945 0.3048)
			(stroke
				(width 0.1)
				(type default)
			)
			(layer "B.Fab")
		)
		(pad "1" smd circle
			(at 0.40005 0)
			(size 0 0)
			(layers "B.Cu" "B.Mask" "B.Paste")
			(net "SMB_HOST_3V3AUX_SCL_R")
		)
		(pad "2" smd circle
			(at -0.40005 0)
			(size 0 0)
			(layers "B.Cu" "B.Mask" "B.Paste")
			(net "SMB_HOST_CLK_3V3AUX_SCL")
		)
	)
	(footprint ""
		(layer "B.Cu")
		(at 416.996626 -164.582602 180)
		(property "Reference" "PR380"
			(at 0 0 0)
			(layer "B.SilkS")
			(hide yes)
			(effects
				(font
					(size 1.27 1.27)
				)
				(justify mirror)
			)
		)
		(property "Value" ""
			(at 0 0 0)
			(layer "B.Fab")
			(effects
				(font
					(size 1.27 1.27)
				)
				(justify mirror)
			)
		)
		(duplicate_pad_numbers_are_jumpers no)
		(fp_line
			(start 0.7874 0.4064)
			(end 0.7874 -0.4064)
			(stroke
				(width 0.1524)
				(type default)
			)
			(layer "B.SilkS")
		)
		(fp_line
			(start 0.7874 -0.4064)
			(end -0.7874 -0.4064)
			(stroke
				(width 0.1524)
				(type default)
			)
			(layer "B.SilkS")
		)
		(fp_line
			(start -0.7874 0.4064)
			(end 0.7874 0.4064)
			(stroke
				(width 0.1524)
				(type default)
			)
			(layer "B.SilkS")
		)
		(fp_line
			(start -0.7874 -0.4064)
			(end -0.7874 0.4064)
			(stroke
				(width 0.1524)
				(type default)
			)
			(layer "B.SilkS")
		)
		(fp_line
			(start 0.67945 0.3048)
			(end 0.67945 -0.305054)
			(stroke
				(width 0.1)
				(type default)
			)
			(layer "B.Fab")
		)
		(fp_line
			(start 0.67945 -0.305054)
			(end 0.12065 -0.305054)
			(stroke
				(width 0.1)
				(type default)
			)
			(layer "B.Fab")
		)
		(fp_line
			(start 0.12065 0.3048)
			(end 0.67945 0.3048)
			(stroke
				(width 0.1)
				(type default)
			)
			(layer "B.Fab")
		)
		(fp_line
			(start 0.12065 0.2794)
			(end 0.12065 0.3048)
			(stroke
				(width 0.1)
				(type default)
			)
			(layer "B.Fab")
		)
		(fp_line
			(start 0.12065 -0.2794)
			(end -0.12065 -0.2794)
			(stroke
				(width 0.1)
				(type default)
			)
			(layer "B.Fab")
		)
		(fp_line
			(start 0.12065 -0.305054)
			(end 0.12065 -0.2794)
			(stroke
				(width 0.1)
				(type default)
			)
			(layer "B.Fab")
		)
		(fp_line
			(start -0.120396 0.3048)
			(end -0.120396 0.2794)
			(stroke
				(width 0.1)
				(type default)
			)
			(layer "B.Fab")
		)
		(fp_line
			(start -0.120396 0.2794)
			(end 0.12065 0.2794)
			(stroke
				(width 0.1)
				(type default)
			)
			(layer "B.Fab")
		)
		(fp_line
			(start -0.12065 -0.2794)
			(end -0.12065 -0.3048)
			(stroke
				(width 0.1)
				(type default)
			)
			(layer "B.Fab")
		)
		(fp_line
			(start -0.12065 -0.3048)
			(end -0.67945 -0.3048)
			(stroke
				(width 0.1)
				(type default)
			)
			(layer "B.Fab")
		)
		(fp_line
			(start -0.67945 0.3048)
			(end -0.120396 0.3048)
			(stroke
				(width 0.1)
				(type default)
			)
			(layer "B.Fab")
		)
		(fp_line
			(start -0.67945 -0.3048)
			(end -0.67945 0.3048)
			(stroke
				(width 0.1)
				(type default)
			)
			(layer "B.Fab")
		)
		(pad "1" smd circle
			(at 0.40005 0)
			(size 0 0)
			(layers "B.Cu" "B.Mask" "B.Paste")
			(net "PVCCFA_EHV_CPU0_PVCC")
		)
		(pad "2" smd circle
			(at -0.40005 0)
			(size 0 0)
			(layers "B.Cu" "B.Mask" "B.Paste")
			(net "PVCCD_HV_CPU0_VDD1")
		)
	)
)
